# SCM (Grand Teton) — schematic netlist excerpt (pin names and nets, part order shuffled) for the footprints in the layout excerpt that follows; sources: Cadence DE-HDL packaged netlist, KiCad conversion of 12092022_DA0F0TMDCD0_F0T_Management_Board_D_brd_V3_OCP.brd

R276  Q_RES  0 5% CHIP  pkg 0402LF  page 55 : A = PWRGD_P1V2_AUX_R ; B = PWRGD_P1V2_AUX
R472  Q_RES  4.7K 1% EMPTY  pkg 0402LF  page 35 : A = P3V3_AUX ; B = AC_PWR_BTN_R1_N

(kicad_pcb
	(version 20260206)
	(generator "pcbnew")
	(generator_version "10.0")
	(general
		(thickness 1.6)
		(legacy_teardrops no)
	)
	(paper "A4")
	(title_block
		(title "12092022_DA0F0TMDCD0_F0T_Management_Board_D_brd_V3_OCP.brd")
		(comment 1 "Grand Teton / footprints 495-496 of 1440")
	)
	(layers
		(0 "F.Cu" signal "TOP")
		(4 "In1.Cu" signal "GND")
		(6 "In2.Cu" signal "IN1")
		(8 "In3.Cu" signal "GND1")
		(10 "In4.Cu" signal "IN2")
		(12 "In5.Cu" signal "VCC")
		(14 "In6.Cu" signal "VCC1")
		(16 "In7.Cu" signal "IN3")
		(18 "In8.Cu" signal "GND2")
		(20 "In9.Cu" signal "IN4")
		(22 "In10.Cu" signal "GND3")
		(2 "B.Cu" signal "BOTTOM")
		(9 "F.Adhes" user "F.Adhesive")
		(11 "B.Adhes" user "B.Adhesive")
		(13 "F.Paste" user "Package Geometry/Pastemask Top")
		(15 "B.Paste" user "Package Geometry/Pastemask Bottom")
		(5 "F.SilkS" user "Ref Des/Silkscreen Top")
		(7 "B.SilkS" user "Ref Des/Silkscreen Bottom")
		(1 "F.Mask" user "Board Geometry/Soldermask Top")
		(3 "B.Mask" user "Board Geometry/Soldermask Bottom")
		(17 "Dwgs.User" user "User.Drawings")
		(19 "Cmts.User" user "User.Comments")
		(21 "Eco1.User" user "User.Eco1")
		(23 "Eco2.User" user "User.Eco2")
		(25 "Edge.Cuts" user "Board Geometry/Outline")
		(27 "Margin" user)
		(31 "F.CrtYd" user "Package Geometry/Place Bound Top")
		(29 "B.CrtYd" user "Package Geometry/Place Bound Bottom")
		(35 "F.Fab" user "Ref Des/Assembly Top")
		(33 "B.Fab" user "Ref Des/Assembly Bottom")
	)
	(footprint ""
		(layer "F.Cu")
		(at 12.4206 -101.0539)
		(property "Reference" "R472"
			(at 0 0 0)
			(layer "F.SilkS")
			(hide yes)
			(effects
				(font
					(size 1.27 1.27)
				)
			)
		)
		(property "Value" ""
			(at 0 0 0)
			(layer "F.Fab")
			(effects
				(font
					(size 1.27 1.27)
				)
			)
		)
		(duplicate_pad_numbers_are_jumpers no)
		(fp_line
			(start -0.7874 -0.4064)
			(end 0.7874 -0.4064)
			(stroke
				(width 0.1524)
				(type default)
			)
			(layer "F.SilkS")
		)
		(fp_line
			(start -0.7874 0.4064)
			(end -0.7874 -0.4064)
			(stroke
				(width 0.1524)
				(type default)
			)
			(layer "F.SilkS")
		)
		(fp_line
			(start 0.7874 -0.4064)
			(end 0.7874 0.4064)
			(stroke
				(width 0.1524)
				(type default)
			)
			(layer "F.SilkS")
		)
		(fp_line
			(start 0.7874 0.4064)
			(end -0.7874 0.4064)
			(stroke
				(width 0.1524)
				(type default)
			)
			(layer "F.SilkS")
		)
		(fp_line
			(start -0.67945 -0.305054)
			(end -0.12065 -0.305054)
			(stroke
				(width 0.1)
				(type default)
			)
			(layer "F.Fab")
		)
		(fp_line
			(start -0.67945 0.3048)
			(end -0.67945 -0.305054)
			(stroke
				(width 0.1)
				(type default)
			)
			(layer "F.Fab")
		)
		(fp_line
			(start -0.12065 -0.305054)
			(end -0.12065 -0.2794)
			(stroke
				(width 0.1)
				(type default)
			)
			(layer "F.Fab")
		)
		(fp_line
			(start -0.12065 -0.2794)
			(end 0.12065 -0.2794)
			(stroke
				(width 0.1)
				(type default)
			)
			(layer "F.Fab")
		)
		(fp_line
			(start -0.12065 0.2794)
			(end -0.12065 0.3048)
			(stroke
				(width 0.1)
				(type default)
			)
			(layer "F.Fab")
		)
		(fp_line
			(start -0.12065 0.3048)
			(end -0.67945 0.3048)
			(stroke
				(width 0.1)
				(type default)
			)
			(layer "F.Fab")
		)
		(fp_line
			(start 0.120396 0.2794)
			(end -0.12065 0.2794)
			(stroke
				(width 0.1)
				(type default)
			)
			(layer "F.Fab")
		)
		(fp_line
			(start 0.120396 0.3048)
			(end 0.120396 0.2794)
			(stroke
				(width 0.1)
				(type default)
			)
			(layer "F.Fab")
		)
		(fp_line
			(start 0.12065 -0.3048)
			(end 0.67945 -0.3048)
			(stroke
				(width 0.1)
				(type default)
			)
			(layer "F.Fab")
		)
		(fp_line
			(start 0.12065 -0.2794)
			(end 0.12065 -0.3048)
			(stroke
				(width 0.1)
				(type default)
			)
			(layer "F.Fab")
		)
		(fp_line
			(start 0.67945 -0.3048)
			(end 0.67945 0.3048)
			(stroke
				(width 0.1)
				(type default)
			)
			(layer "F.Fab")
		)
		(fp_line
			(start 0.67945 0.3048)
			(end 0.120396 0.3048)
			(stroke
				(width 0.1)
				(type default)
			)
			(layer "F.Fab")
		)
		(pad "1" smd circle
			(at -0.40005 0)
			(size 0 0)
			(layers "F.Cu" "F.Mask" "F.Paste")
			(net "P3V3_AUX")
		)
		(pad "2" smd circle
			(at 0.40005 0)
			(size 0 0)
			(layers "F.Cu" "F.Mask" "F.Paste")
			(net "AC_PWR_BTN_R1_N")
		)
	)
	(footprint ""
		(layer "F.Cu")
		(at 84.455 -76.6572 90)
		(property "Reference" "R276"
			(at 0 0 90)
			(layer "F.SilkS")
			(hide yes)
			(effects
				(font
					(size 1.27 1.27)
				)
			)
		)
		(property "Value" ""
			(at 0 0 90)
			(layer "F.Fab")
			(effects
				(font
					(size 1.27 1.27)
				)
			)
		)
		(duplicate_pad_numbers_are_jumpers no)
		(fp_line
			(start 0.7874 -0.4064)
			(end 0.7874 0.4064)
			(stroke
				(width 0.1524)
				(type default)
			)
			(layer "F.SilkS")
		)
		(fp_line
			(start -0.7874 -0.4064)
			(end 0.7874 -0.4064)
			(stroke
				(width 0.1524)
				(type default)
			)
			(layer "F.SilkS")
		)
		(fp_line
			(start 0.7874 0.4064)
			(end -0.7874 0.4064)
			(stroke
				(width 0.1524)
				(type default)
			)
			(layer "F.SilkS")
		)
		(fp_line
			(start -0.7874 0.4064)
			(end -0.7874 -0.4064)
			(stroke
				(width 0.1524)
				(type default)
			)
			(layer "F.SilkS")
		)
		(fp_line
			(start -0.12065 -0.305054)
			(end -0.12065 -0.2794)
			(stroke
				(width 0.1)
				(type default)
			)
			(layer "F.Fab")
		)
		(fp_line
			(start -0.67945 -0.305054)
			(end -0.12065 -0.305054)
			(stroke
				(width 0.1)
				(type default)
			)
			(layer "F.Fab")
		)
		(fp_line
			(start 0.67945 -0.3048)
			(end 0.67945 0.3048)
			(stroke
				(width 0.1)
				(type default)
			)
			(layer "F.Fab")
		)
		(fp_line
			(start 0.12065 -0.3048)
			(end 0.67945 -0.3048)
			(stroke
				(width 0.1)
				(type default)
			)
			(layer "F.Fab")
		)
		(fp_line
			(start 0.12065 -0.2794)
			(end 0.12065 -0.3048)
			(stroke
				(width 0.1)
				(type default)
			)
			(layer "F.Fab")
		)
		(fp_line
			(start -0.12065 -0.2794)
			(end 0.12065 -0.2794)
			(stroke
				(width 0.1)
				(type default)
			)
			(layer "F.Fab")
		)
		(fp_line
			(start 0.120396 0.2794)
			(end -0.12065 0.2794)
			(stroke
				(width 0.1)
				(type default)
			)
			(layer "F.Fab")
		)
		(fp_line
			(start -0.12065 0.2794)
			(end -0.12065 0.3048)
			(stroke
				(width 0.1)
				(type default)
			)
			(layer "F.Fab")
		)
		(fp_line
			(start 0.67945 0.3048)
			(end 0.120396 0.3048)
			(stroke
				(width 0.1)
				(type default)
			)
			(layer "F.Fab")
		)
		(fp_line
			(start 0.120396 0.3048)
			(end 0.120396 0.2794)
			(stroke
				(width 0.1)
				(type default)
			)
			(layer "F.Fab")
		)
		(fp_line
			(start -0.12065 0.3048)
			(end -0.67945 0.3048)
			(stroke
				(width 0.1)
				(type default)
			)
			(layer "F.Fab")
		)
		(fp_line
			(start -0.67945 0.3048)
			(end -0.67945 -0.305054)
			(stroke
				(width 0.1)
				(type default)
			)
			(layer "F.Fab")
		)
		(pad "1" smd circle
			(at -0.40005 0 90)
			(size 0 0)
			(layers "F.Cu" "F.Mask" "F.Paste")
			(net "PWRGD_P1V2_AUX_R")
		)
		(pad "2" smd circle
			(at 0.40005 0 90)
			(size 0 0)
			(layers "F.Cu" "F.Mask" "F.Paste")
			(net "PWRGD_P1V2_AUX")
		)
	)
)
